(kicad_pcb
	(version 20260206)
	(generator "pcbnew")
	(generator_version "10.0")
	(general
		(thickness 1.6)
		(legacy_teardrops no)
	)
	(paper "A4")
	(title_block
		(title "pdpb — Lightning_PDPB_BRD.brd")
		(comment 1 "Lightning (Wiwynn / Facebook NVMe JBOF) / footprints 352-358 of 1140")
	)
	(layers
		(0 "F.Cu" signal "TOP")
		(4 "In1.Cu" signal "L2GND")
		(6 "In2.Cu" signal "L3")
		(8 "In3.Cu" signal "L4VCC")
		(10 "In4.Cu" signal "L5VCC")
		(12 "In5.Cu" signal "L6")
		(14 "In6.Cu" signal "L7GND")
		(2 "B.Cu" signal "BOTTOM")
		(9 "F.Adhes" user "F.Adhesive")
		(11 "B.Adhes" user "B.Adhesive")
		(13 "F.Paste" user "Package Geometry/Pastemask Top")
		(15 "B.Paste" user "Package Geometry/Pastemask Bottom")
		(5 "F.SilkS" user "Ref Des/Silkscreen Top")
		(7 "B.SilkS" user "Ref Des/Silkscreen Bottom")
		(1 "F.Mask" user "Board Geometry/Soldermask Top")
		(3 "B.Mask" user "Board Geometry/Soldermask Bottom")
		(17 "Dwgs.User" user "User.Drawings")
		(19 "Cmts.User" user "User.Comments")
		(21 "Eco1.User" user "User.Eco1")
		(23 "Eco2.User" user "User.Eco2")
		(25 "Edge.Cuts" user "Board Geometry/Outline")
		(27 "Margin" user)
		(31 "F.CrtYd" user "Package Geometry/Place Bound Top")
		(29 "B.CrtYd" user "Package Geometry/Place Bound Bottom")
		(35 "F.Fab" user "Ref Des/Assembly Top")
		(33 "B.Fab" user "Ref Des/Assembly Bottom")
	)
	(footprint ""
		(layer "F.Cu")
		(at 30.8864 -12.5984 180)
		(property "Reference" "SR1120"
			(at 0 0 180)
			(layer "F.SilkS")
			(hide yes)
			(effects
				(font
					(size 1.27 1.27)
				)
			)
		)
		(property "Value" "4K7R2F-GP"
			(at 0.064008 -3.993896 180)
			(unlocked yes)
			(layer "F.Fab")
			(hide yes)
			(effects
				(font
					(size 1.016 1.016)
					(thickness 0.1524)
				)
			)
		)
		(property "Device Type" "R402H16"
			(at 0.064008 -5.517896 180)
			(unlocked yes)
			(layer "F.Fab")
			(hide yes)
			(effects
				(font
					(size 1.016 1.016)
					(thickness 0.1524)
				)
			)
		)
		(duplicate_pad_numbers_are_jumpers no)
		(fp_line
			(start 0.508 -0.9398)
			(end -0.508 -0.9398)
			(stroke
				(width 0.1524)
				(type default)
			)
			(layer "F.SilkS")
		)
		(fp_line
			(start -0.508 -0.9398)
			(end -0.508 0.9398)
			(stroke
				(width 0.1524)
				(type default)
			)
			(layer "F.SilkS")
		)
		(fp_rect
			(start -0.508 0.9398)
			(end 0.508 -0.9398)
			(stroke
				(width 0)
				(type default)
			)
			(fill no)
			(layer "F.CrtYd")
		)
		(fp_rect
			(start -0.508 0.9398)
			(end 0.508 -0.9398)
			(stroke
				(width 0)
				(type default)
			)
			(fill no)
			(layer "F.Fab")
		)
		(pad "1" smd custom
			(at 0 -0.4445 180)
			(size 0.1397 0.1397)
			(layers "F.Cu" "F.Mask" "F.Paste")
			(net "DUALPORTEN#14")
			(options
				(clearance outline)
				(anchor circle)
			)
			(primitives
				(gr_poly
					(pts
						(arc
							(start -0.1778 -0.2794)
							(mid -0.249642 -0.249642)
							(end -0.2794 -0.1778)
						)
						(arc
							(start -0.2794 0.1778)
							(mid -0.249642 0.249642)
							(end -0.1778 0.2794)
						)
						(arc
							(start 0.1778 0.2794)
							(mid 0.249642 0.249642)
							(end 0.2794 0.1778)
						)
						(arc
							(start 0.2794 -0.1778)
							(mid 0.249642 -0.249642)
							(end 0.1778 -0.2794)
						)
					)
					(width 0)
					(fill yes)
				)
			)
		)
		(pad "2" smd custom
			(at 0 0.4445 180)
			(size 0.1397 0.1397)
			(layers "F.Cu" "F.Mask" "F.Paste")
			(net "GND")
			(options
				(clearance outline)
				(anchor circle)
			)
			(primitives
				(gr_poly
					(pts
						(arc
							(start -0.1778 -0.2794)
							(mid -0.249642 -0.249642)
							(end -0.2794 -0.1778)
						)
						(arc
							(start -0.2794 0.1778)
							(mid -0.249642 0.249642)
							(end -0.1778 0.2794)
						)
						(arc
							(start 0.1778 0.2794)
							(mid 0.249642 0.249642)
							(end 0.2794 0.1778)
						)
						(arc
							(start 0.2794 -0.1778)
							(mid 0.249642 -0.249642)
							(end 0.1778 -0.2794)
						)
					)
					(width 0)
					(fill yes)
				)
			)
		)
	)
	(footprint ""
		(layer "F.Cu")
		(at 224.623122 -427.609 -90)
		(property "Reference" "PC1284"
			(at 0 0 270)
			(layer "F.SilkS")
			(hide yes)
			(effects
				(font
					(size 1.27 1.27)
				)
			)
		)
		(property "Value" "SC22U25V6KX-GP-U"
			(at -2.860802 -5.279644 270)
			(unlocked yes)
			(layer "F.Fab")
			(hide yes)
			(effects
				(font
					(size 1.016 1.016)
					(thickness 0.1524)
				)
			)
		)
		(property "Device Type" "C1206-TO0D3H75"
			(at -2.860802 -6.803644 270)
			(unlocked yes)
			(layer "F.Fab")
			(hide yes)
			(effects
				(font
					(size 1.016 1.016)
					(thickness 0.1524)
				)
			)
		)
		(duplicate_pad_numbers_are_jumpers no)
		(fp_line
			(start -1.3081 2.3749)
			(end -1.3081 -2.3749)
			(stroke
				(width 0.1524)
				(type default)
			)
			(layer "F.SilkS")
		)
		(fp_line
			(start 1.3081 2.3749)
			(end -1.3081 2.3749)
			(stroke
				(width 0.1524)
				(type default)
			)
			(layer "F.SilkS")
		)
		(fp_line
			(start -1.3081 -2.3749)
			(end 1.3081 -2.3749)
			(stroke
				(width 0.1524)
				(type default)
			)
			(layer "F.SilkS")
		)
		(fp_line
			(start 1.3081 -2.3749)
			(end 1.3081 2.3749)
			(stroke
				(width 0.1524)
				(type default)
			)
			(layer "F.SilkS")
		)
		(fp_rect
			(start -0.8001 1.6002)
			(end 0.8001 -1.6002)
			(stroke
				(width 0)
				(type default)
			)
			(fill no)
			(layer "F.CrtYd")
		)
		(fp_poly
			(pts
				(xy -1.5621 2.4511) (xy -1.5621 1.6002) (xy 0.8001 1.6002) (xy 0.8001 -1.6002) (xy -0.8001 -1.6002)
				(xy -0.8001 1.5875) (xy -1.5621 1.5875) (xy -1.5621 -2.4511) (xy 1.5621 -2.4511) (xy 1.5621 2.4511)
			)
			(stroke
				(width 0)
				(type default)
			)
			(fill no)
			(layer "F.CrtYd")
		)
		(fp_rect
			(start -1.5621 2.4511)
			(end 1.5621 -2.4511)
			(stroke
				(width 0)
				(type default)
			)
			(fill no)
			(layer "F.Fab")
		)
		(pad "1" smd rect
			(at 0 -1.392936 270)
			(size 2.1082 1.4478)
			(layers "F.Cu" "F.Mask" "F.Paste")
			(net "P3V3_VIN")
		)
		(pad "2" smd rect
			(at 0 1.392936 270)
			(size 2.1082 1.4478)
			(layers "F.Cu" "F.Mask" "F.Paste")
			(net "GND")
		)
	)
	(footprint ""
		(layer "F.Cu")
		(at 88.011 -89.535 90)
		(property "Reference" "C9337"
			(at 0 0 90)
			(layer "F.SilkS")
			(hide yes)
			(effects
				(font
					(size 1.27 1.27)
				)
			)
		)
		(property "Value" "SC1KP50V2KX-1GP"
			(at 1.1811 -2.7051 90)
			(unlocked yes)
			(layer "F.Fab")
			(hide yes)
			(effects
				(font
					(size 1.016 1.016)
					(thickness 0.1524)
				)
			)
		)
		(property "Device Type" "C402H22"
			(at 1.1811 -4.2291 90)
			(unlocked yes)
			(layer "F.Fab")
			(hide yes)
			(effects
				(font
					(size 1.016 1.016)
					(thickness 0.1524)
				)
			)
		)
		(duplicate_pad_numbers_are_jumpers no)
		(fp_rect
			(start -0.4318 0.9525)
			(end 0.4318 -0.9525)
			(stroke
				(width 0)
				(type default)
			)
			(fill no)
			(layer "F.CrtYd")
		)
		(fp_rect
			(start -0.4318 0.9525)
			(end 0.4318 -0.9525)
			(stroke
				(width 0)
				(type default)
			)
			(fill no)
			(layer "F.Fab")
		)
		(pad "1" smd custom
			(at 0 -0.4445 90)
			(size 0.1524 0.1524)
			(layers "F.Cu" "F.Mask" "F.Paste")
			(net "SSD_PRSNT9")
			(options
				(clearance outline)
				(anchor circle)
			)
			(primitives
				(gr_poly
					(pts
						(arc
							(start 0.3048 -0.2032)
							(mid 0.275042 -0.275042)
							(end 0.2032 -0.3048)
						)
						(arc
							(start -0.2032 -0.3048)
							(mid -0.275042 -0.275042)
							(end -0.3048 -0.2032)
						)
						(arc
							(start -0.3048 0.2032)
							(mid -0.275042 0.275042)
							(end -0.2032 0.3048)
						)
						(arc
							(start 0.2032 0.3048)
							(mid 0.275042 0.275042)
							(end 0.3048 0.2032)
						)
					)
					(width 0)
					(fill yes)
				)
			)
		)
		(pad "2" smd custom
			(at 0 0.4445 90)
			(size 0.1524 0.1524)
			(layers "F.Cu" "F.Mask" "F.Paste")
			(net "GND")
			(options
				(clearance outline)
				(anchor circle)
			)
			(primitives
				(gr_poly
					(pts
						(arc
							(start 0.3048 -0.2032)
							(mid 0.275042 -0.275042)
							(end 0.2032 -0.3048)
						)
						(arc
							(start -0.2032 -0.3048)
							(mid -0.275042 -0.275042)
							(end -0.3048 -0.2032)
						)
						(arc
							(start -0.3048 0.2032)
							(mid -0.275042 0.275042)
							(end -0.2032 0.3048)
						)
						(arc
							(start 0.2032 0.3048)
							(mid 0.275042 0.275042)
							(end 0.3048 0.2032)
						)
					)
					(width 0)
					(fill yes)
				)
			)
		)
	)
	(footprint ""
		(layer "F.Cu")
		(at 217.4494 -187.579 180)
		(property "Reference" "SR1098"
			(at 0 0 180)
			(layer "F.SilkS")
			(hide yes)
			(effects
				(font
					(size 1.27 1.27)
				)
			)
		)
		(property "Value" "4K7R2F-GP"
			(at 0.064008 -3.993896 180)
			(unlocked yes)
			(layer "F.Fab")
			(hide yes)
			(effects
				(font
					(size 1.016 1.016)
					(thickness 0.1524)
				)
			)
		)
		(property "Device Type" "R402H16"
			(at 0.064008 -5.517896 180)
			(unlocked yes)
			(layer "F.Fab")
			(hide yes)
			(effects
				(font
					(size 1.016 1.016)
					(thickness 0.1524)
				)
			)
		)
		(duplicate_pad_numbers_are_jumpers no)
		(fp_line
			(start 0.508 -0.9398)
			(end -0.508 -0.9398)
			(stroke
				(width 0.1524)
				(type default)
			)
			(layer "F.SilkS")
		)
		(fp_line
			(start -0.508 -0.9398)
			(end -0.508 0.9398)
			(stroke
				(width 0.1524)
				(type default)
			)
			(layer "F.SilkS")
		)
		(fp_rect
			(start -0.508 0.9398)
			(end 0.508 -0.9398)
			(stroke
				(width 0)
				(type default)
			)
			(fill no)
			(layer "F.CrtYd")
		)
		(fp_rect
			(start -0.508 0.9398)
			(end 0.508 -0.9398)
			(stroke
				(width 0)
				(type default)
			)
			(fill no)
			(layer "F.Fab")
		)
		(pad "1" smd custom
			(at 0 -0.4445 180)
			(size 0.1397 0.1397)
			(layers "F.Cu" "F.Mask" "F.Paste")
			(net "DUALPORTEN#3")
			(options
				(clearance outline)
				(anchor circle)
			)
			(primitives
				(gr_poly
					(pts
						(arc
							(start -0.1778 -0.2794)
							(mid -0.249642 -0.249642)
							(end -0.2794 -0.1778)
						)
						(arc
							(start -0.2794 0.1778)
							(mid -0.249642 0.249642)
							(end -0.1778 0.2794)
						)
						(arc
							(start 0.1778 0.2794)
							(mid 0.249642 0.249642)
							(end 0.2794 0.1778)
						)
						(arc
							(start 0.2794 -0.1778)
							(mid 0.249642 -0.249642)
							(end 0.1778 -0.2794)
						)
					)
					(width 0)
					(fill yes)
				)
			)
		)
		(pad "2" smd custom
			(at 0 0.4445 180)
			(size 0.1397 0.1397)
			(layers "F.Cu" "F.Mask" "F.Paste")
			(net "GND")
			(options
				(clearance outline)
				(anchor circle)
			)
			(primitives
				(gr_poly
					(pts
						(arc
							(start -0.1778 -0.2794)
							(mid -0.249642 -0.249642)
							(end -0.2794 -0.1778)
						)
						(arc
							(start -0.2794 0.1778)
							(mid -0.249642 0.249642)
							(end -0.1778 0.2794)
						)
						(arc
							(start 0.1778 0.2794)
							(mid 0.249642 0.249642)
							(end 0.2794 0.1778)
						)
						(arc
							(start 0.2794 -0.1778)
							(mid 0.249642 -0.249642)
							(end 0.1778 -0.2794)
						)
					)
					(width 0)
					(fill yes)
				)
			)
		)
	)
	(footprint ""
		(layer "F.Cu")
		(at 43.50004 -350.099884)
		(property "Reference" "LED6"
			(at 0 0 0)
			(layer "F.SilkS")
			(hide yes)
			(effects
				(font
					(size 1.27 1.27)
				)
			)
		)
		(property "Value" "LED-RB-4-GP"
			(at 5.88899 1.80848 0)
			(unlocked yes)
			(layer "F.Fab")
			(hide yes)
			(effects
				(font
					(size 1.016 1.016)
					(thickness 0.1524)
				)
			)
		)
		(property "Device Type" "LED1613-4PH20"
			(at 5.88899 0.28448 0)
			(unlocked yes)
			(layer "F.Fab")
			(hide yes)
			(effects
				(font
					(size 1.016 1.016)
					(thickness 0.1524)
				)
			)
		)
		(duplicate_pad_numbers_are_jumpers no)
		(fp_line
			(start -1.4478 -0.9652)
			(end 1.4478 -0.9652)
			(stroke
				(width 0.1524)
				(type default)
			)
			(layer "F.SilkS")
		)
		(fp_line
			(start -1.4478 0.9652)
			(end -1.4478 -0.9652)
			(stroke
				(width 0.1524)
				(type default)
			)
			(layer "F.SilkS")
		)
		(fp_line
			(start -1.4478 0.9652)
			(end -1.4478 -0.9652)
			(stroke
				(width 0.508)
				(type default)
			)
			(layer "F.SilkS")
		)
		(fp_line
			(start 1.4478 -0.9652)
			(end 1.4478 0.9652)
			(stroke
				(width 0.1524)
				(type default)
			)
			(layer "F.SilkS")
		)
		(fp_line
			(start 1.4478 0.9652)
			(end -1.4478 0.9652)
			(stroke
				(width 0.1524)
				(type default)
			)
			(layer "F.SilkS")
		)
		(fp_rect
			(start -0.8001 0.6477)
			(end 0.8001 -0.6477)
			(stroke
				(width 0)
				(type default)
			)
			(fill no)
			(layer "F.CrtYd")
		)
		(fp_poly
			(pts
				(xy -1.7018 1.2192) (xy -1.7018 -0.06223) (xy -0.8001 -0.06223) (xy -0.8001 0.6477) (xy 0.8001 0.6477)
				(xy 0.8001 -0.6477) (xy -0.8001 -0.6477) (xy -0.8001 -0.0635) (xy -1.7018 -0.0635) (xy -1.7018 -1.2192)
				(xy 1.7018 -1.2192) (xy 1.7018 1.2192)
			)
			(stroke
				(width 0)
				(type default)
			)
			(fill no)
			(layer "F.CrtYd")
		)
		(fp_rect
			(start -1.7018 1.2192)
			(end 1.7018 -1.2192)
			(stroke
				(width 0)
				(type default)
			)
			(fill no)
			(layer "F.Fab")
		)
		(pad "1" smd rect
			(at -0.73025 0.4064)
			(size 0.9144 0.6096)
			(layers "F.Cu" "F.Mask" "F.Paste")
			(net "SSD_ACT_DR6_MOS_N")
		)
		(pad "2" smd rect
			(at -0.73025 -0.4064)
			(size 0.9144 0.6096)
			(layers "F.Cu" "F.Mask" "F.Paste")
			(net "ATTN_LED_DR6_MOS_N")
		)
		(pad "3" smd rect
			(at 0.73025 -0.4064)
			(size 0.9144 0.6096)
			(layers "F.Cu" "F.Mask" "F.Paste")
			(net "DRV_ATTN_6")
		)
		(pad "4" smd rect
			(at 0.73025 0.4064)
			(size 0.9144 0.6096)
			(layers "F.Cu" "F.Mask" "F.Paste")
			(net "DRV_ACT_6")
		)
	)
	(footprint ""
		(layer "F.Cu")
		(at 33.1089 -205.4479)
		(property "Reference" "R9860"
			(at 0 0 0)
			(layer "F.SilkS")
			(hide yes)
			(effects
				(font
					(size 1.27 1.27)
				)
			)
		)
		(property "Value" "47KR2J-2-GP"
			(at 0.064008 -3.993896 0)
			(unlocked yes)
			(layer "F.Fab")
			(hide yes)
			(effects
				(font
					(size 1.016 1.016)
					(thickness 0.1524)
				)
			)
		)
		(property "Device Type" "R402H16"
			(at 0.064008 -5.517896 0)
			(unlocked yes)
			(layer "F.Fab")
			(hide yes)
			(effects
				(font
					(size 1.016 1.016)
					(thickness 0.1524)
				)
			)
		)
		(duplicate_pad_numbers_are_jumpers no)
		(fp_line
			(start -0.508 -0.9398)
			(end -0.508 0.9398)
			(stroke
				(width 0.1524)
				(type default)
			)
			(layer "F.SilkS")
		)
		(fp_line
			(start 0.508 -0.9398)
			(end -0.508 -0.9398)
			(stroke
				(width 0.1524)
				(type default)
			)
			(layer "F.SilkS")
		)
		(fp_rect
			(start -0.508 0.9398)
			(end 0.508 -0.9398)
			(stroke
				(width 0)
				(type default)
			)
			(fill no)
			(layer "F.CrtYd")
		)
		(fp_rect
			(start -0.508 0.9398)
			(end 0.508 -0.9398)
			(stroke
				(width 0)
				(type default)
			)
			(fill no)
			(layer "F.Fab")
		)
		(pad "1" smd custom
			(at 0 -0.4445)
			(size 0.1397 0.1397)
			(layers "F.Cu" "F.Mask" "F.Paste")
			(net "P12V")
			(options
				(clearance outline)
				(anchor circle)
			)
			(primitives
				(gr_poly
					(pts
						(arc
							(start -0.1778 -0.2794)
							(mid -0.249642 -0.249642)
							(end -0.2794 -0.1778)
						)
						(arc
							(start -0.2794 0.1778)
							(mid -0.249642 0.249642)
							(end -0.1778 0.2794)
						)
						(arc
							(start 0.1778 0.2794)
							(mid 0.249642 0.249642)
							(end 0.2794 0.1778)
						)
						(arc
							(start 0.2794 -0.1778)
							(mid 0.249642 -0.249642)
							(end 0.1778 -0.2794)
						)
					)
					(width 0)
					(fill yes)
				)
			)
		)
		(pad "2" smd custom
			(at 0 0.4445)
			(size 0.1397 0.1397)
			(layers "F.Cu" "F.Mask" "F.Paste")
			(net "P12V_MOST12_GATE")
			(options
				(clearance outline)
				(anchor circle)
			)
			(primitives
				(gr_poly
					(pts
						(arc
							(start -0.1778 -0.2794)
							(mid -0.249642 -0.249642)
							(end -0.2794 -0.1778)
						)
						(arc
							(start -0.2794 0.1778)
							(mid -0.249642 0.249642)
							(end -0.1778 0.2794)
						)
						(arc
							(start 0.1778 0.2794)
							(mid 0.249642 0.249642)
							(end 0.2794 0.1778)
						)
						(arc
							(start 0.2794 -0.1778)
							(mid 0.249642 -0.249642)
							(end 0.1778 -0.2794)
						)
					)
					(width 0)
					(fill yes)
				)
			)
		)
	)
	(footprint ""
		(layer "F.Cu")
		(at 234.061 -451.485 -90)
		(property "Reference" "R9892"
			(at 0 0 270)
			(layer "F.SilkS")
			(hide yes)
			(effects
				(font
					(size 1.27 1.27)
				)
			)
		)
		(property "Value" "1K82R2F-1-GP"
			(at 0.064008 -3.993896 270)
			(unlocked yes)
			(layer "F.Fab")
			(hide yes)
			(effects
				(font
					(size 1.016 1.016)
					(thickness 0.1524)
				)
			)
		)
		(property "Device Type" "R402H16"
			(at 0.064008 -5.517896 270)
			(unlocked yes)
			(layer "F.Fab")
			(hide yes)
			(effects
				(font
					(size 1.016 1.016)
					(thickness 0.1524)
				)
			)
		)
		(duplicate_pad_numbers_are_jumpers no)
		(fp_line
			(start -0.508 -0.9398)
			(end -0.508 0.9398)
			(stroke
				(width 0.1524)
				(type default)
			)
			(layer "F.SilkS")
		)
		(fp_line
			(start 0.508 -0.9398)
			(end -0.508 -0.9398)
			(stroke
				(width 0.1524)
				(type default)
			)
			(layer "F.SilkS")
		)
		(fp_rect
			(start -0.508 0.9398)
			(end 0.508 -0.9398)
			(stroke
				(width 0)
				(type default)
			)
			(fill no)
			(layer "F.CrtYd")
		)
		(fp_rect
			(start -0.508 0.9398)
			(end 0.508 -0.9398)
			(stroke
				(width 0)
				(type default)
			)
			(fill no)
			(layer "F.Fab")
		)
		(pad "1" smd custom
			(at 0 -0.4445 270)
			(size 0.1397 0.1397)
			(layers "F.Cu" "F.Mask" "F.Paste")
			(net "P12V")
			(options
				(clearance outline)
				(anchor circle)
			)
			(primitives
				(gr_poly
					(pts
						(arc
							(start -0.1778 -0.2794)
							(mid -0.249642 -0.249642)
							(end -0.2794 -0.1778)
						)
						(arc
							(start -0.2794 0.1778)
							(mid -0.249642 0.249642)
							(end -0.1778 0.2794)
						)
						(arc
							(start 0.1778 0.2794)
							(mid 0.249642 0.249642)
							(end 0.2794 0.1778)
						)
						(arc
							(start 0.2794 -0.1778)
							(mid 0.249642 -0.249642)
							(end 0.1778 -0.2794)
						)
					)
					(width 0)
					(fill yes)
				)
			)
		)
		(pad "2" smd custom
			(at 0 0.4445 270)
			(size 0.1397 0.1397)
			(layers "F.Cu" "F.Mask" "F.Paste")
			(net "DRV_ACT_0")
			(options
				(clearance outline)
				(anchor circle)
			)
			(primitives
				(gr_poly
					(pts
						(arc
							(start -0.1778 -0.2794)
							(mid -0.249642 -0.249642)
							(end -0.2794 -0.1778)
						)
						(arc
							(start -0.2794 0.1778)
							(mid -0.249642 0.249642)
							(end -0.1778 0.2794)
						)
						(arc
							(start 0.1778 0.2794)
							(mid 0.249642 0.249642)
							(end 0.2794 0.1778)
						)
						(arc
							(start 0.2794 -0.1778)
							(mid 0.249642 -0.249642)
							(end 0.1778 -0.2794)
						)
					)
					(width 0)
					(fill yes)
				)
			)
		)
	)
)
